;LEADER: 12 
;HEADER: 
;CODE  : ASCII 
;FILE  : 9324_DA0F0TMBIJ0_F0T_Motherboard_J_v01_20230324_0910-bd-1-11.drl for backdrilling ... from layer TOP to layer GND4
;DESIGN: 9324_DA0F0TMBIJ0_F0T_Motherboard_J_v01_20230324_0910.brd
;MUST-NOT-CUT-LAYER = IN4,  MAX_DRILL_DEPTH = 61.30 MILS,  MFG_STUB_LENGTH = 0.00 MILS
;   BackdrillSize 1. = 17.700000 Tolerance = +0.000000/-0.000000 NON_PLATED MILS Quantity = 8
%
G90
X0723041Y-0023200
X0723041Y-0019800
X0840001Y0010200
X0840001Y0006800
X0980899Y0010200
X0980899Y0006800
X0980899Y-0023200
X0980899Y-0019800
M30
